(kicad_pcb
	(version 20260206)
	(generator "pcbnew")
	(generator_version "10.0")
	(general
		(thickness 1.6)
		(legacy_teardrops no)
	)
	(paper "A4")
	(title_block
		(title "baseboard — 13948-1b.1110WZS1818.brd")
		(comment 1 "Honey Badger (Wiwynn) / footprints 1995-2002 of 2523")
	)
	(layers
		(0 "F.Cu" signal "TOP")
		(4 "In1.Cu" signal "L2GND")
		(6 "In2.Cu" signal "L3")
		(8 "In3.Cu" signal "L4VCC")
		(10 "In4.Cu" signal "L5VCC")
		(12 "In5.Cu" signal "L6")
		(14 "In6.Cu" signal "L7GND")
		(2 "B.Cu" signal "BOTTOM")
		(9 "F.Adhes" user "F.Adhesive")
		(11 "B.Adhes" user "B.Adhesive")
		(13 "F.Paste" user "Package Geometry/Pastemask Top")
		(15 "B.Paste" user "Package Geometry/Pastemask Bottom")
		(5 "F.SilkS" user "Ref Des/Silkscreen Top")
		(7 "B.SilkS" user "Ref Des/Silkscreen Bottom")
		(1 "F.Mask" user "Board Geometry/Soldermask Top")
		(3 "B.Mask" user "Board Geometry/Soldermask Bottom")
		(17 "Dwgs.User" user "User.Drawings")
		(19 "Cmts.User" user "User.Comments")
		(21 "Eco1.User" user "User.Eco1")
		(23 "Eco2.User" user "User.Eco2")
		(25 "Edge.Cuts" user "Board Geometry/Outline")
		(27 "Margin" user)
		(31 "F.CrtYd" user "Package Geometry/Place Bound Top")
		(29 "B.CrtYd" user "Package Geometry/Place Bound Bottom")
		(35 "F.Fab" user "Ref Des/Assembly Top")
		(33 "B.Fab" user "Ref Des/Assembly Bottom")
	)
	(footprint ""
		(layer "B.Cu")
		(at 111.195612 -222.885 180)
		(property "Reference" "SR894"
			(at 0 0 0)
			(layer "B.SilkS")
			(hide yes)
			(effects
				(font
					(size 1.27 1.27)
				)
				(justify mirror)
			)
		)
		(property "Value" "0R2J-2-GP"
			(at -0.064008 -3.993896 180)
			(unlocked yes)
			(layer "B.Fab")
			(hide yes)
			(effects
				(font
					(size 1.016 1.016)
					(thickness 0.1524)
				)
				(justify mirror)
			)
		)
		(property "Device Type" "R402H16"
			(at -0.064008 -5.517896 180)
			(unlocked yes)
			(layer "B.Fab")
			(hide yes)
			(effects
				(font
					(size 1.016 1.016)
					(thickness 0.1524)
				)
				(justify mirror)
			)
		)
		(duplicate_pad_numbers_are_jumpers no)
		(fp_line
			(start 0.508 -0.9398)
			(end 0.508 0.9398)
			(stroke
				(width 0.1524)
				(type default)
			)
			(layer "B.SilkS")
		)
		(fp_line
			(start -0.508 -0.9398)
			(end 0.508 -0.9398)
			(stroke
				(width 0.1524)
				(type default)
			)
			(layer "B.SilkS")
		)
		(fp_rect
			(start 0.508 0.9398)
			(end -0.508 -0.9398)
			(stroke
				(width 0)
				(type default)
			)
			(fill no)
			(layer "B.CrtYd")
		)
		(fp_rect
			(start 0.508 0.9398)
			(end -0.508 -0.9398)
			(stroke
				(width 0)
				(type default)
			)
			(fill no)
			(layer "B.Fab")
		)
		(pad "1" smd custom
			(at 0 -0.4445)
			(size 0.1397 0.1397)
			(layers "B.Cu" "B.Mask" "B.Paste")
			(net "SAS_GF_EXP_RX_DP8")
			(options
				(clearance outline)
				(anchor circle)
			)
			(primitives
				(gr_poly
					(pts
						(arc
							(start -0.1778 0.2794)
							(mid -0.249642 0.249642)
							(end -0.2794 0.1778)
						)
						(arc
							(start -0.2794 -0.1778)
							(mid -0.249642 -0.249642)
							(end -0.1778 -0.2794)
						)
						(arc
							(start 0.1778 -0.2794)
							(mid 0.249642 -0.249642)
							(end 0.2794 -0.1778)
						)
						(arc
							(start 0.2794 0.1778)
							(mid 0.249642 0.249642)
							(end 0.1778 0.2794)
						)
					)
					(width 0)
					(fill yes)
				)
			)
		)
		(pad "2" smd custom
			(at 0 0.4445)
			(size 0.1397 0.1397)
			(layers "B.Cu" "B.Mask" "B.Paste")
			(net "REDV_RX8_P")
			(options
				(clearance outline)
				(anchor circle)
			)
			(primitives
				(gr_poly
					(pts
						(arc
							(start -0.1778 0.2794)
							(mid -0.249642 0.249642)
							(end -0.2794 0.1778)
						)
						(arc
							(start -0.2794 -0.1778)
							(mid -0.249642 -0.249642)
							(end -0.1778 -0.2794)
						)
						(arc
							(start 0.1778 -0.2794)
							(mid 0.249642 -0.249642)
							(end 0.2794 -0.1778)
						)
						(arc
							(start 0.2794 0.1778)
							(mid 0.249642 0.249642)
							(end 0.1778 0.2794)
						)
					)
					(width 0)
					(fill yes)
				)
			)
		)
	)
	(footprint ""
		(layer "B.Cu")
		(at 98.1202 -41.402)
		(property "Reference" "SC1048"
			(at 0 0 0)
			(layer "B.SilkS")
			(hide yes)
			(effects
				(font
					(size 1.27 1.27)
				)
				(justify mirror)
			)
		)
		(property "Value" "SCD1U16V2KX-3GP"
			(at -1.1811 -2.7051 0)
			(unlocked yes)
			(layer "B.Fab")
			(hide yes)
			(effects
				(font
					(size 1.016 1.016)
					(thickness 0.1524)
				)
				(justify mirror)
			)
		)
		(property "Device Type" "C402H22"
			(at -1.1811 -4.2291 0)
			(unlocked yes)
			(layer "B.Fab")
			(hide yes)
			(effects
				(font
					(size 1.016 1.016)
					(thickness 0.1524)
				)
				(justify mirror)
			)
		)
		(duplicate_pad_numbers_are_jumpers no)
		(fp_rect
			(start 0.4318 0.9525)
			(end -0.4318 -0.9525)
			(stroke
				(width 0)
				(type default)
			)
			(fill no)
			(layer "B.CrtYd")
		)
		(fp_rect
			(start 0.4318 0.9525)
			(end -0.4318 -0.9525)
			(stroke
				(width 0)
				(type default)
			)
			(fill no)
			(layer "B.Fab")
		)
		(pad "1" smd custom
			(at 0 -0.4445 180)
			(size 0.1524 0.1524)
			(layers "B.Cu" "B.Mask" "B.Paste")
			(net "P0V955_C")
			(options
				(clearance outline)
				(anchor circle)
			)
			(primitives
				(gr_poly
					(pts
						(arc
							(start 0.3048 0.2032)
							(mid 0.275042 0.275042)
							(end 0.2032 0.3048)
						)
						(arc
							(start -0.2032 0.3048)
							(mid -0.275042 0.275042)
							(end -0.3048 0.2032)
						)
						(arc
							(start -0.3048 -0.2032)
							(mid -0.275042 -0.275042)
							(end -0.2032 -0.3048)
						)
						(arc
							(start 0.2032 -0.3048)
							(mid 0.275042 -0.275042)
							(end 0.3048 -0.2032)
						)
					)
					(width 0)
					(fill yes)
				)
			)
		)
		(pad "2" smd custom
			(at 0 0.4445 180)
			(size 0.1524 0.1524)
			(layers "B.Cu" "B.Mask" "B.Paste")
			(net "GND")
			(options
				(clearance outline)
				(anchor circle)
			)
			(primitives
				(gr_poly
					(pts
						(arc
							(start 0.3048 0.2032)
							(mid 0.275042 0.275042)
							(end 0.2032 0.3048)
						)
						(arc
							(start -0.2032 0.3048)
							(mid -0.275042 0.275042)
							(end -0.3048 0.2032)
						)
						(arc
							(start -0.3048 -0.2032)
							(mid -0.275042 -0.275042)
							(end -0.2032 -0.3048)
						)
						(arc
							(start 0.2032 -0.3048)
							(mid 0.275042 -0.275042)
							(end 0.3048 -0.2032)
						)
					)
					(width 0)
					(fill yes)
				)
			)
		)
	)
	(footprint ""
		(layer "B.Cu")
		(at 274.193 -169.545 90)
		(property "Reference" "R240"
			(at 0 0 90)
			(layer "B.SilkS")
			(hide yes)
			(effects
				(font
					(size 1.27 1.27)
				)
				(justify mirror)
			)
		)
		(property "Value" "0R2J-2-GP"
			(at -0.064008 -3.993896 90)
			(unlocked yes)
			(layer "B.Fab")
			(hide yes)
			(effects
				(font
					(size 1.016 1.016)
					(thickness 0.1524)
				)
				(justify mirror)
			)
		)
		(property "Device Type" "R402H16"
			(at -0.064008 -5.517896 90)
			(unlocked yes)
			(layer "B.Fab")
			(hide yes)
			(effects
				(font
					(size 1.016 1.016)
					(thickness 0.1524)
				)
				(justify mirror)
			)
		)
		(duplicate_pad_numbers_are_jumpers no)
		(fp_line
			(start 0.508 -0.9398)
			(end 0.508 0.9398)
			(stroke
				(width 0.1524)
				(type default)
			)
			(layer "B.SilkS")
		)
		(fp_line
			(start -0.508 -0.9398)
			(end 0.508 -0.9398)
			(stroke
				(width 0.1524)
				(type default)
			)
			(layer "B.SilkS")
		)
		(fp_rect
			(start 0.508 0.9398)
			(end -0.508 -0.9398)
			(stroke
				(width 0)
				(type default)
			)
			(fill no)
			(layer "B.CrtYd")
		)
		(fp_rect
			(start 0.508 0.9398)
			(end -0.508 -0.9398)
			(stroke
				(width 0)
				(type default)
			)
			(fill no)
			(layer "B.Fab")
		)
		(pad "1" smd custom
			(at 0 -0.4445 270)
			(size 0.1397 0.1397)
			(layers "B.Cu" "B.Mask" "B.Paste")
			(net "BMC_10G_SCL_2")
			(options
				(clearance outline)
				(anchor circle)
			)
			(primitives
				(gr_poly
					(pts
						(arc
							(start -0.1778 0.2794)
							(mid -0.249642 0.249642)
							(end -0.2794 0.1778)
						)
						(arc
							(start -0.2794 -0.1778)
							(mid -0.249642 -0.249642)
							(end -0.1778 -0.2794)
						)
						(arc
							(start 0.1778 -0.2794)
							(mid 0.249642 -0.249642)
							(end 0.2794 -0.1778)
						)
						(arc
							(start 0.2794 0.1778)
							(mid 0.249642 0.249642)
							(end 0.1778 0.2794)
						)
					)
					(width 0)
					(fill yes)
				)
			)
		)
		(pad "2" smd custom
			(at 0 0.4445 270)
			(size 0.1397 0.1397)
			(layers "B.Cu" "B.Mask" "B.Paste")
			(net "BMC0_SMB2_CLK")
			(options
				(clearance outline)
				(anchor circle)
			)
			(primitives
				(gr_poly
					(pts
						(arc
							(start -0.1778 0.2794)
							(mid -0.249642 0.249642)
							(end -0.2794 0.1778)
						)
						(arc
							(start -0.2794 -0.1778)
							(mid -0.249642 -0.249642)
							(end -0.1778 -0.2794)
						)
						(arc
							(start 0.1778 -0.2794)
							(mid 0.249642 -0.249642)
							(end 0.2794 -0.1778)
						)
						(arc
							(start 0.2794 0.1778)
							(mid 0.249642 0.249642)
							(end 0.1778 0.2794)
						)
					)
					(width 0)
					(fill yes)
				)
			)
		)
	)
	(footprint ""
		(layer "B.Cu")
		(at 87.916766 -47.8028)
		(property "Reference" "STP3"
			(at 0 0 0)
			(layer "B.SilkS")
			(hide yes)
			(effects
				(font
					(size 1.27 1.27)
				)
				(justify mirror)
			)
		)
		(property "Value" "TPAD28"
			(at -0.0127 -1.8034 0)
			(unlocked yes)
			(layer "B.Fab")
			(hide yes)
			(effects
				(font
					(size 1.016 1.016)
					(thickness 0.1524)
				)
				(justify mirror)
			)
		)
		(property "Device Type" "TPAD28"
			(at -0.0127 -3.3274 0)
			(unlocked yes)
			(layer "B.Fab")
			(hide yes)
			(effects
				(font
					(size 1.016 1.016)
					(thickness 0.1524)
				)
				(justify mirror)
			)
		)
		(duplicate_pad_numbers_are_jumpers no)
		(fp_poly
			(pts
				(arc
					(start 0.3556 0)
					(mid -0.3556 0)
					(end 0.3556 0)
				)
			)
			(stroke
				(width 0)
				(type default)
			)
			(fill no)
			(layer "B.CrtYd")
		)
		(fp_poly
			(pts
				(arc
					(start 0.6096 0)
					(mid -0.6096 0)
					(end 0.6096 0)
				)
			)
			(stroke
				(width 0)
				(type default)
			)
			(fill no)
			(layer "B.Fab")
		)
		(pad "1" smd circle
			(at 0 0 180)
			(size 0.7112 0.7112)
			(layers "B.Cu" "B.Mask" "B.Paste")
			(net "SIO_CLK_0")
		)
	)
	(footprint ""
		(layer "B.Cu")
		(at 319.405 -181.737 -90)
		(property "Reference" "R5772"
			(at 0 0 90)
			(layer "B.SilkS")
			(hide yes)
			(effects
				(font
					(size 1.27 1.27)
				)
				(justify mirror)
			)
		)
		(property "Value" "1KR2F-3-GP"
			(at -0.064008 -3.993896 270)
			(unlocked yes)
			(layer "B.Fab")
			(hide yes)
			(effects
				(font
					(size 1.016 1.016)
					(thickness 0.1524)
				)
				(justify mirror)
			)
		)
		(property "Device Type" "R402H16"
			(at -0.064008 -5.517896 270)
			(unlocked yes)
			(layer "B.Fab")
			(hide yes)
			(effects
				(font
					(size 1.016 1.016)
					(thickness 0.1524)
				)
				(justify mirror)
			)
		)
		(duplicate_pad_numbers_are_jumpers no)
		(fp_line
			(start -0.508 -0.9398)
			(end 0.508 -0.9398)
			(stroke
				(width 0.1524)
				(type default)
			)
			(layer "B.SilkS")
		)
		(fp_line
			(start 0.508 -0.9398)
			(end 0.508 0.9398)
			(stroke
				(width 0.1524)
				(type default)
			)
			(layer "B.SilkS")
		)
		(fp_rect
			(start 0.508 0.9398)
			(end -0.508 -0.9398)
			(stroke
				(width 0)
				(type default)
			)
			(fill no)
			(layer "B.CrtYd")
		)
		(fp_rect
			(start 0.508 0.9398)
			(end -0.508 -0.9398)
			(stroke
				(width 0)
				(type default)
			)
			(fill no)
			(layer "B.Fab")
		)
		(pad "1" smd custom
			(at 0 -0.4445 90)
			(size 0.1397 0.1397)
			(layers "B.Cu" "B.Mask" "B.Paste")
			(net "P1V5_E")
			(options
				(clearance outline)
				(anchor circle)
			)
			(primitives
				(gr_poly
					(pts
						(arc
							(start -0.1778 0.2794)
							(mid -0.249642 0.249642)
							(end -0.2794 0.1778)
						)
						(arc
							(start -0.2794 -0.1778)
							(mid -0.249642 -0.249642)
							(end -0.1778 -0.2794)
						)
						(arc
							(start 0.1778 -0.2794)
							(mid 0.249642 -0.249642)
							(end 0.2794 -0.1778)
						)
						(arc
							(start 0.2794 0.1778)
							(mid 0.249642 0.249642)
							(end 0.1778 0.2794)
						)
					)
					(width 0)
					(fill yes)
				)
			)
		)
		(pad "2" smd custom
			(at 0 0.4445 90)
			(size 0.1397 0.1397)
			(layers "B.Cu" "B.Mask" "B.Paste")
			(net "ADC_P1V5_E")
			(options
				(clearance outline)
				(anchor circle)
			)
			(primitives
				(gr_poly
					(pts
						(arc
							(start -0.1778 0.2794)
							(mid -0.249642 0.249642)
							(end -0.2794 0.1778)
						)
						(arc
							(start -0.2794 -0.1778)
							(mid -0.249642 -0.249642)
							(end -0.1778 -0.2794)
						)
						(arc
							(start 0.1778 -0.2794)
							(mid 0.249642 -0.249642)
							(end 0.2794 -0.1778)
						)
						(arc
							(start 0.2794 0.1778)
							(mid 0.249642 0.249642)
							(end 0.1778 0.2794)
						)
					)
					(width 0)
					(fill yes)
				)
			)
		)
	)
	(footprint ""
		(layer "B.Cu")
		(at 318.008 -179.705 -90)
		(property "Reference" "R321"
			(at 0 0 90)
			(layer "B.SilkS")
			(hide yes)
			(effects
				(font
					(size 1.27 1.27)
				)
				(justify mirror)
			)
		)
		(property "Value" "0R2J-2-GP"
			(at -0.064008 -3.993896 270)
			(unlocked yes)
			(layer "B.Fab")
			(hide yes)
			(effects
				(font
					(size 1.016 1.016)
					(thickness 0.1524)
				)
				(justify mirror)
			)
		)
		(property "Device Type" "R402H16"
			(at -0.064008 -5.517896 270)
			(unlocked yes)
			(layer "B.Fab")
			(hide yes)
			(effects
				(font
					(size 1.016 1.016)
					(thickness 0.1524)
				)
				(justify mirror)
			)
		)
		(duplicate_pad_numbers_are_jumpers no)
		(fp_line
			(start -0.508 -0.9398)
			(end 0.508 -0.9398)
			(stroke
				(width 0.1524)
				(type default)
			)
			(layer "B.SilkS")
		)
		(fp_line
			(start 0.508 -0.9398)
			(end 0.508 0.9398)
			(stroke
				(width 0.1524)
				(type default)
			)
			(layer "B.SilkS")
		)
		(fp_rect
			(start 0.508 0.9398)
			(end -0.508 -0.9398)
			(stroke
				(width 0)
				(type default)
			)
			(fill no)
			(layer "B.CrtYd")
		)
		(fp_rect
			(start 0.508 0.9398)
			(end -0.508 -0.9398)
			(stroke
				(width 0)
				(type default)
			)
			(fill no)
			(layer "B.Fab")
		)
		(pad "1" smd custom
			(at 0 -0.4445 90)
			(size 0.1397 0.1397)
			(layers "B.Cu" "B.Mask" "B.Paste")
			(net "ADC_P0V955_C")
			(options
				(clearance outline)
				(anchor circle)
			)
			(primitives
				(gr_poly
					(pts
						(arc
							(start -0.1778 0.2794)
							(mid -0.249642 0.249642)
							(end -0.2794 0.1778)
						)
						(arc
							(start -0.2794 -0.1778)
							(mid -0.249642 -0.249642)
							(end -0.1778 -0.2794)
						)
						(arc
							(start 0.1778 -0.2794)
							(mid 0.249642 -0.249642)
							(end 0.2794 -0.1778)
						)
						(arc
							(start 0.2794 0.1778)
							(mid 0.249642 0.249642)
							(end 0.1778 0.2794)
						)
					)
					(width 0)
					(fill yes)
				)
			)
		)
		(pad "2" smd custom
			(at 0 0.4445 90)
			(size 0.1397 0.1397)
			(layers "B.Cu" "B.Mask" "B.Paste")
			(net "ADC_P0V955_C_BMC")
			(options
				(clearance outline)
				(anchor circle)
			)
			(primitives
				(gr_poly
					(pts
						(arc
							(start -0.1778 0.2794)
							(mid -0.249642 0.249642)
							(end -0.2794 0.1778)
						)
						(arc
							(start -0.2794 -0.1778)
							(mid -0.249642 -0.249642)
							(end -0.1778 -0.2794)
						)
						(arc
							(start 0.1778 -0.2794)
							(mid 0.249642 -0.249642)
							(end 0.2794 -0.1778)
						)
						(arc
							(start 0.2794 0.1778)
							(mid 0.249642 0.249642)
							(end 0.1778 0.2794)
						)
					)
					(width 0)
					(fill yes)
				)
			)
		)
	)
	(footprint ""
		(layer "B.Cu")
		(at 101.454966 -40.386)
		(property "Reference" "SC1060"
			(at 0 0 0)
			(layer "B.SilkS")
			(hide yes)
			(effects
				(font
					(size 1.27 1.27)
				)
				(justify mirror)
			)
		)
		(property "Value" "SCD1U16V2KX-3GP"
			(at -1.1811 -2.7051 0)
			(unlocked yes)
			(layer "B.Fab")
			(hide yes)
			(effects
				(font
					(size 1.016 1.016)
					(thickness 0.1524)
				)
				(justify mirror)
			)
		)
		(property "Device Type" "C402H22"
			(at -1.1811 -4.2291 0)
			(unlocked yes)
			(layer "B.Fab")
			(hide yes)
			(effects
				(font
					(size 1.016 1.016)
					(thickness 0.1524)
				)
				(justify mirror)
			)
		)
		(duplicate_pad_numbers_are_jumpers no)
		(fp_rect
			(start 0.4318 0.9525)
			(end -0.4318 -0.9525)
			(stroke
				(width 0)
				(type default)
			)
			(fill no)
			(layer "B.CrtYd")
		)
		(fp_rect
			(start 0.4318 0.9525)
			(end -0.4318 -0.9525)
			(stroke
				(width 0)
				(type default)
			)
			(fill no)
			(layer "B.Fab")
		)
		(pad "1" smd custom
			(at 0 -0.4445 180)
			(size 0.1524 0.1524)
			(layers "B.Cu" "B.Mask" "B.Paste")
			(net "P0V955_C")
			(options
				(clearance outline)
				(anchor circle)
			)
			(primitives
				(gr_poly
					(pts
						(arc
							(start 0.3048 0.2032)
							(mid 0.275042 0.275042)
							(end 0.2032 0.3048)
						)
						(arc
							(start -0.2032 0.3048)
							(mid -0.275042 0.275042)
							(end -0.3048 0.2032)
						)
						(arc
							(start -0.3048 -0.2032)
							(mid -0.275042 -0.275042)
							(end -0.2032 -0.3048)
						)
						(arc
							(start 0.2032 -0.3048)
							(mid 0.275042 -0.275042)
							(end 0.3048 -0.2032)
						)
					)
					(width 0)
					(fill yes)
				)
			)
		)
		(pad "2" smd custom
			(at 0 0.4445 180)
			(size 0.1524 0.1524)
			(layers "B.Cu" "B.Mask" "B.Paste")
			(net "GND")
			(options
				(clearance outline)
				(anchor circle)
			)
			(primitives
				(gr_poly
					(pts
						(arc
							(start 0.3048 0.2032)
							(mid 0.275042 0.275042)
							(end 0.2032 0.3048)
						)
						(arc
							(start -0.2032 0.3048)
							(mid -0.275042 0.275042)
							(end -0.3048 0.2032)
						)
						(arc
							(start -0.3048 -0.2032)
							(mid -0.275042 -0.275042)
							(end -0.2032 -0.3048)
						)
						(arc
							(start 0.2032 -0.3048)
							(mid 0.275042 -0.275042)
							(end 0.3048 -0.2032)
						)
					)
					(width 0)
					(fill yes)
				)
			)
		)
	)
	(footprint ""
		(layer "B.Cu")
		(at 302.45304 -182.7403)
		(property "Reference" "TP101"
			(at 0 0 0)
			(layer "B.SilkS")
			(hide yes)
			(effects
				(font
					(size 1.27 1.27)
				)
				(justify mirror)
			)
		)
		(property "Value" "TPAD28"
			(at -0.0127 -1.8034 0)
			(unlocked yes)
			(layer "B.Fab")
			(hide yes)
			(effects
				(font
					(size 1.016 1.016)
					(thickness 0.1524)
				)
				(justify mirror)
			)
		)
		(property "Device Type" "TPAD28"
			(at -0.0127 -3.3274 0)
			(unlocked yes)
			(layer "B.Fab")
			(hide yes)
			(effects
				(font
					(size 1.016 1.016)
					(thickness 0.1524)
				)
				(justify mirror)
			)
		)
		(duplicate_pad_numbers_are_jumpers no)
		(fp_poly
			(pts
				(arc
					(start 0.3556 0)
					(mid -0.3556 0)
					(end 0.3556 0)
				)
			)
			(stroke
				(width 0)
				(type default)
			)
			(fill no)
			(layer "B.CrtYd")
		)
		(fp_poly
			(pts
				(arc
					(start 0.6096 0)
					(mid -0.6096 0)
					(end 0.6096 0)
				)
			)
			(stroke
				(width 0)
				(type default)
			)
			(fill no)
			(layer "B.Fab")
		)
		(pad "1" smd circle
			(at 0 0 180)
			(size 0.7112 0.7112)
			(layers "B.Cu" "B.Mask" "B.Paste")
			(net "TP_BMC_GPIOL2")
		)
	)
)
